# TIMECARD (Time Appliance Project (Time Card)) — schematic netlist excerpt (pin names and nets, part order shuffled) for the footprints in the layout excerpt that follows; sources: Cadence DE-HDL packaged netlist, KiCad conversion of R4006-B0001-02_R01.brd

C302  CAPACITOR  0.1UF 25V 10%  pkg SMC_0402R_H022  page 33 : \1\ = UNNAMED_525_CAPACITOR_I14_1 ; \2\ = SG
R289  RESISTOR  4.7KOHM 1%  pkg SMC_0402R_H016  page 20 : \1\ = XP3R3V_FPGA ; \2\ = FPGA_IN_BNO080_INT_N

(kicad_pcb
	(version 20260206)
	(generator "pcbnew")
	(generator_version "10.0")
	(general
		(thickness 1.6)
		(legacy_teardrops no)
	)
	(paper "A4")
	(title_block
		(title "timecard-production-celestica-r4006 — R4006-B0001-02_R01.brd")
		(comment 1 "Time Appliance Project (Time Card) / footprints 188-190 of 1113")
	)
	(layers
		(0 "F.Cu" signal "TOP")
		(4 "In1.Cu" signal "L02_GND1")
		(6 "In2.Cu" signal "L03_SIG1")
		(8 "In3.Cu" signal "L04_GND2")
		(10 "In4.Cu" signal "L05_VCC1")
		(12 "In5.Cu" signal "L06_VCC2")
		(14 "In6.Cu" signal "L07_GND3")
		(16 "In7.Cu" signal "L08_SIG2")
		(18 "In8.Cu" signal "L09_GND4")
		(2 "B.Cu" signal "BOTTOM")
		(9 "F.Adhes" user "F.Adhesive")
		(11 "B.Adhes" user "B.Adhesive")
		(13 "F.Paste" user "Package Geometry/Pastemask Top")
		(15 "B.Paste" user "Package Geometry/Pastemask Bottom")
		(5 "F.SilkS" user "Ref Des/Silkscreen Top")
		(7 "B.SilkS" user "Ref Des/Silkscreen Bottom")
		(1 "F.Mask" user "Board Geometry/Soldermask Top")
		(3 "B.Mask" user "Board Geometry/Soldermask Bottom")
		(17 "Dwgs.User" user "User.Drawings")
		(19 "Cmts.User" user "User.Comments")
		(21 "Eco1.User" user "User.Eco1")
		(23 "Eco2.User" user "User.Eco2")
		(25 "Edge.Cuts" user "Board Geometry/Outline")
		(27 "Margin" user)
		(31 "F.CrtYd" user "Package Geometry/Place Bound Top")
		(29 "B.CrtYd" user "Package Geometry/Place Bound Bottom")
		(35 "F.Fab" user "Ref Des/Assembly Top")
		(33 "B.Fab" user "Ref Des/Assembly Bottom")
	)
	(footprint ""
		(layer "F.Cu")
		(at 80.772 -56.1086 180)
		(property "Reference" "R289"
			(at 10.287 19.51863 0)
			(unlocked yes)
			(layer "F.SilkS")
			(effects
				(font
					(size 0.7874 0.5842)
					(thickness 0.1524)
				)
			)
		)
		(property "Value" "VAL*"
			(at 0.02032 2.13233 180)
			(unlocked yes)
			(layer "F.Fab")
			(hide yes)
			(effects
				(font
					(size 0.7874 0.5842)
					(thickness 0.1524)
				)
			)
		)
		(property "Tolerance" "TOL*"
			(at 0.044704 3.05435 180)
			(unlocked yes)
			(layer "Cmts.User")
			(hide yes)
			(effects
				(font
					(size 0.7874 0.5842)
					(thickness 0.1524)
				)
			)
		)
		(property "User Part Number" "PARTNUM*"
			(at 0.02032 4.024884 180)
			(unlocked yes)
			(layer "Cmts.User")
			(hide yes)
			(effects
				(font
					(size 0.7874 0.5842)
					(thickness 0.1524)
				)
			)
		)
		(property "Device Type" "RESISTOR-G155-14701-01,4.7KOHMA"
			(at 0.008382 1.210564 180)
			(unlocked yes)
			(layer "F.Fab")
			(hide yes)
			(effects
				(font
					(size 0.7874 0.5842)
					(thickness 0.1524)
				)
			)
		)
		(duplicate_pad_numbers_are_jumpers no)
		(fp_line
			(start 1.143 0.5588)
			(end 1.143 -0.5588)
			(stroke
				(width 0.1)
				(type default)
			)
			(layer "F.SilkS")
		)
		(fp_line
			(start 1.143 -0.5588)
			(end -1.143 -0.5588)
			(stroke
				(width 0.1)
				(type default)
			)
			(layer "F.SilkS")
		)
		(fp_line
			(start -1.143 0.5588)
			(end 1.143 0.5588)
			(stroke
				(width 0.1)
				(type default)
			)
			(layer "F.SilkS")
		)
		(fp_line
			(start -1.143 -0.5588)
			(end -1.143 0.5588)
			(stroke
				(width 0.1)
				(type default)
			)
			(layer "F.SilkS")
		)
		(fp_rect
			(start 1.143 -0.5588)
			(end -1.143 0.5588)
			(stroke
				(width 0)
				(type default)
			)
			(fill no)
			(layer "F.CrtYd")
		)
		(fp_line
			(start 0.508 0.3048)
			(end 0.508 -0.3048)
			(stroke
				(width 0.1)
				(type default)
			)
			(layer "F.Fab")
		)
		(fp_line
			(start 0.508 -0.3048)
			(end -0.508 -0.3048)
			(stroke
				(width 0.1)
				(type default)
			)
			(layer "F.Fab")
		)
		(fp_line
			(start -0.508 0.3048)
			(end 0.508 0.3048)
			(stroke
				(width 0.1)
				(type default)
			)
			(layer "F.Fab")
		)
		(fp_line
			(start -0.508 -0.3048)
			(end -0.508 0.3048)
			(stroke
				(width 0.1)
				(type default)
			)
			(layer "F.Fab")
		)
		(pad "1" smd rect
			(at -0.5334 0 180)
			(size 0.7112 0.6096)
			(layers "F.Cu" "F.Mask" "F.Paste")
			(net "XP3R3V_FPGA")
		)
		(pad "2" smd rect
			(at 0.5334 0 180)
			(size 0.7112 0.6096)
			(layers "F.Cu" "F.Mask" "F.Paste")
			(net "FPGA_IN_BNO080_INT_N")
		)
		(zone
			(layer "F.Cu")
			(hatch none 0.5)
			(connect_pads
				(clearance 0)
			)
			(min_thickness 0.25)
			(keepout
				(tracks allowed)
				(vias not_allowed)
				(pads allowed)
				(copperpour not_allowed)
				(footprints allowed)
			)
			(placement
				(enabled no)
				(sheetname "")
			)
			(fill
				(thermal_gap 0.5)
				(thermal_bridge_width 0.5)
				(island_removal_mode 0)
			)
			(polygon
				(pts
					(xy 80.6958 -55.8038) (xy 80.8482 -55.8038) (xy 80.8482 -56.4134) (xy 80.6958 -56.4134)
				)
			)
		)
	)
	(footprint ""
		(layer "F.Cu")
		(at 47.879 -75.184 90)
		(property "Reference" "C302"
			(at -0.381 2.19837 90)
			(unlocked yes)
			(layer "F.SilkS")
			(effects
				(font
					(size 0.7874 0.5842)
					(thickness 0.1524)
				)
			)
		)
		(property "Value" "VAL*"
			(at 0.0762 2.067306 90)
			(unlocked yes)
			(layer "F.Fab")
			(hide yes)
			(effects
				(font
					(size 0.7874 0.5842)
					(thickness 0.1524)
				)
			)
		)
		(property "Tolerance" "TOL*"
			(at 0.0762 3.032506 90)
			(unlocked yes)
			(layer "Cmts.User")
			(hide yes)
			(effects
				(font
					(size 0.7874 0.5842)
					(thickness 0.1524)
				)
			)
		)
		(property "User Part Number" "PARTNUM*"
			(at 0.1016 4.023106 90)
			(unlocked yes)
			(layer "Cmts.User")
			(hide yes)
			(effects
				(font
					(size 0.7874 0.5842)
					(thickness 0.1524)
				)
			)
		)
		(property "Device Type" "CAPACITOR-G105-0B104-EK,0.1UF,A"
			(at 0.0508 1.127506 90)
			(unlocked yes)
			(layer "F.Fab")
			(hide yes)
			(effects
				(font
					(size 0.7874 0.5842)
					(thickness 0.1524)
				)
			)
		)
		(duplicate_pad_numbers_are_jumpers no)
		(fp_line
			(start 1.143 -0.5588)
			(end -1.143 -0.5588)
			(stroke
				(width 0.1)
				(type default)
			)
			(layer "F.SilkS")
		)
		(fp_line
			(start -1.143 -0.5588)
			(end -1.143 0.5588)
			(stroke
				(width 0.1)
				(type default)
			)
			(layer "F.SilkS")
		)
		(fp_line
			(start 1.143 0.5588)
			(end 1.143 -0.5588)
			(stroke
				(width 0.1)
				(type default)
			)
			(layer "F.SilkS")
		)
		(fp_line
			(start -1.143 0.5588)
			(end 1.143 0.5588)
			(stroke
				(width 0.1)
				(type default)
			)
			(layer "F.SilkS")
		)
		(fp_poly
			(pts
				(xy -1.143 0.5588) (xy 1.143 0.5588) (xy 1.143 -0.5588) (xy -1.143 -0.5588)
			)
			(stroke
				(width 0)
				(type default)
			)
			(fill no)
			(layer "F.CrtYd")
		)
		(fp_line
			(start 0.508 -0.3048)
			(end -0.508 -0.3048)
			(stroke
				(width 0.1)
				(type default)
			)
			(layer "F.Fab")
		)
		(fp_line
			(start -0.508 -0.3048)
			(end -0.508 0.3048)
			(stroke
				(width 0.1)
				(type default)
			)
			(layer "F.Fab")
		)
		(fp_line
			(start 0.508 0.3048)
			(end 0.508 -0.3048)
			(stroke
				(width 0.1)
				(type default)
			)
			(layer "F.Fab")
		)
		(fp_line
			(start -0.508 0.3048)
			(end 0.508 0.3048)
			(stroke
				(width 0.1)
				(type default)
			)
			(layer "F.Fab")
		)
		(pad "1" smd rect
			(at -0.5334 0 90)
			(size 0.7112 0.6096)
			(layers "F.Cu" "F.Mask" "F.Paste")
			(net "UNNAMED_525_CAPACITOR_I14_1")
		)
		(pad "2" smd rect
			(at 0.5334 0 90)
			(size 0.7112 0.6096)
			(layers "F.Cu" "F.Mask" "F.Paste")
			(net "SG")
		)
		(zone
			(layer "F.Cu")
			(hatch none 0.5)
			(connect_pads
				(clearance 0)
			)
			(min_thickness 0.25)
			(keepout
				(tracks not_allowed)
				(vias allowed)
				(pads allowed)
				(copperpour not_allowed)
				(footprints allowed)
			)
			(placement
				(enabled no)
				(sheetname "")
			)
			(fill
				(thermal_gap 0.5)
				(thermal_bridge_width 0.5)
				(island_removal_mode 0)
			)
			(polygon
				(pts
					(xy 48.1838 -75.1078) (xy 48.1838 -75.2602) (xy 47.5742 -75.2602) (xy 47.5742 -75.1078)
				)
			)
		)
		(zone
			(layer "F.Cu")
			(hatch none 0.5)
			(connect_pads
				(clearance 0)
			)
			(min_thickness 0.25)
			(keepout
				(tracks allowed)
				(vias not_allowed)
				(pads allowed)
				(copperpour not_allowed)
				(footprints allowed)
			)
			(placement
				(enabled no)
				(sheetname "")
			)
			(fill
				(thermal_gap 0.5)
				(thermal_bridge_width 0.5)
				(island_removal_mode 0)
			)
			(polygon
				(pts
					(xy 48.1838 -75.1078) (xy 48.1838 -75.2602) (xy 47.5742 -75.2602) (xy 47.5742 -75.1078)
				)
			)
		)
	)
	(footprint ""
		(layer "F.Cu")
		(at 52.451 -122.428)
		(property "Reference" "SP78"
			(at 0 0 0)
			(layer "F.SilkS")
			(hide yes)
			(effects
				(font
					(size 1.27 1.27)
				)
			)
		)
		(property "Value" ""
			(at 0 0 0)
			(layer "F.Fab")
			(effects
				(font
					(size 1.27 1.27)
				)
			)
		)
		(duplicate_pad_numbers_are_jumpers no)
	)
)
